# T6G (Grand Teton) — schematic netlist excerpt (pin names and nets, part order shuffled) for the footprints in the layout excerpt that follows; sources: Cadence DE-HDL packaged netlist, KiCad conversion of 04192023_DAF0TMB3IC0_F0TG_MB_C_brd_V02_OCP.brd

R2848  Q_RES  0 5% CHIP  pkg 0402LF  page 245 : A = RST_SWB_BIC_N ; B = RST_SWB_BIC_R_N
C725  Q_CAP_DIFFBUS  DIFF BUS_0.22UF 6.3V 20% X6S  pkg C0201  page 66 : \1\ = P5E_CPU1_P1_TX_C_DP<8> ; \2\ = P5E_CPU1_P1_TX_DP<8>
PR3841  Q_RES  120K 1% CHIP  pkg 0402LF  page 135 : A = P12V_AUX ; B = P12V_OCP_OV_FB_1

(kicad_pcb
	(version 20260206)
	(generator "pcbnew")
	(generator_version "10.0")
	(general
		(thickness 1.6)
		(legacy_teardrops no)
	)
	(paper "A4")
	(title_block
		(title "04192023_DAF0TMB3IC0_F0TG_MB_C_brd_V02_OCP.brd")
		(comment 1 "Grand Teton / footprints 4781-4783 of 8354")
	)
	(layers
		(0 "F.Cu" signal "TOP")
		(4 "In1.Cu" signal "GND")
		(6 "In2.Cu" signal "IN1")
		(8 "In3.Cu" signal "GND1")
		(10 "In4.Cu" signal "IN2")
		(12 "In5.Cu" signal "GND2")
		(14 "In6.Cu" signal "IN3")
		(16 "In7.Cu" signal "GND3")
		(18 "In8.Cu" signal "VCC")
		(20 "In9.Cu" signal "VCC1")
		(22 "In10.Cu" signal "GND4")
		(24 "In11.Cu" signal "IN4")
		(26 "In12.Cu" signal "GND5")
		(28 "In13.Cu" signal "IN5")
		(30 "In14.Cu" signal "GND6")
		(32 "In15.Cu" signal "IN6")
		(34 "In16.Cu" signal "GND7")
		(2 "B.Cu" signal "BOTTOM")
		(9 "F.Adhes" user "F.Adhesive")
		(11 "B.Adhes" user "B.Adhesive")
		(13 "F.Paste" user "Package Geometry/Pastemask Top")
		(15 "B.Paste" user "Package Geometry/Pastemask Bottom")
		(5 "F.SilkS" user "Ref Des/Silkscreen Top")
		(7 "B.SilkS" user "Ref Des/Silkscreen Bottom")
		(1 "F.Mask" user "Board Geometry/Soldermask Top")
		(3 "B.Mask" user "Board Geometry/Soldermask Bottom")
		(17 "Dwgs.User" user "User.Drawings")
		(19 "Cmts.User" user "User.Comments")
		(21 "Eco1.User" user "User.Eco1")
		(23 "Eco2.User" user "User.Eco2")
		(25 "Edge.Cuts" user "Board Geometry/Outline")
		(27 "Margin" user)
		(31 "F.CrtYd" user "Package Geometry/Place Bound Top")
		(29 "B.CrtYd" user "Package Geometry/Place Bound Bottom")
		(35 "F.Fab" user "Ref Des/Assembly Top")
		(33 "B.Fab" user "Ref Des/Assembly Bottom")
	)
	(footprint ""
		(layer "F.Cu")
		(at 437.542432 -27.275536 90)
		(property "Reference" "PR3841"
			(at 0 0 90)
			(layer "F.SilkS")
			(hide yes)
			(effects
				(font
					(size 1.27 1.27)
				)
			)
		)
		(property "Value" ""
			(at 0 0 90)
			(layer "F.Fab")
			(effects
				(font
					(size 1.27 1.27)
				)
			)
		)
		(duplicate_pad_numbers_are_jumpers no)
		(fp_line
			(start 0.7874 -0.4064)
			(end 0.7874 0.4064)
			(stroke
				(width 0.1524)
				(type default)
			)
			(layer "F.SilkS")
		)
		(fp_line
			(start -0.7874 -0.4064)
			(end 0.7874 -0.4064)
			(stroke
				(width 0.1524)
				(type default)
			)
			(layer "F.SilkS")
		)
		(fp_line
			(start 0.7874 0.4064)
			(end -0.7874 0.4064)
			(stroke
				(width 0.1524)
				(type default)
			)
			(layer "F.SilkS")
		)
		(fp_line
			(start -0.7874 0.4064)
			(end -0.7874 -0.4064)
			(stroke
				(width 0.1524)
				(type default)
			)
			(layer "F.SilkS")
		)
		(fp_line
			(start -0.12065 -0.305054)
			(end -0.12065 -0.2794)
			(stroke
				(width 0.1)
				(type default)
			)
			(layer "F.Fab")
		)
		(fp_line
			(start -0.67945 -0.305054)
			(end -0.12065 -0.305054)
			(stroke
				(width 0.1)
				(type default)
			)
			(layer "F.Fab")
		)
		(fp_line
			(start 0.67945 -0.3048)
			(end 0.67945 0.3048)
			(stroke
				(width 0.1)
				(type default)
			)
			(layer "F.Fab")
		)
		(fp_line
			(start 0.12065 -0.3048)
			(end 0.67945 -0.3048)
			(stroke
				(width 0.1)
				(type default)
			)
			(layer "F.Fab")
		)
		(fp_line
			(start 0.12065 -0.2794)
			(end 0.12065 -0.3048)
			(stroke
				(width 0.1)
				(type default)
			)
			(layer "F.Fab")
		)
		(fp_line
			(start -0.12065 -0.2794)
			(end 0.12065 -0.2794)
			(stroke
				(width 0.1)
				(type default)
			)
			(layer "F.Fab")
		)
		(fp_line
			(start 0.120396 0.2794)
			(end -0.12065 0.2794)
			(stroke
				(width 0.1)
				(type default)
			)
			(layer "F.Fab")
		)
		(fp_line
			(start -0.12065 0.2794)
			(end -0.12065 0.3048)
			(stroke
				(width 0.1)
				(type default)
			)
			(layer "F.Fab")
		)
		(fp_line
			(start 0.67945 0.3048)
			(end 0.120396 0.3048)
			(stroke
				(width 0.1)
				(type default)
			)
			(layer "F.Fab")
		)
		(fp_line
			(start 0.120396 0.3048)
			(end 0.120396 0.2794)
			(stroke
				(width 0.1)
				(type default)
			)
			(layer "F.Fab")
		)
		(fp_line
			(start -0.12065 0.3048)
			(end -0.67945 0.3048)
			(stroke
				(width 0.1)
				(type default)
			)
			(layer "F.Fab")
		)
		(fp_line
			(start -0.67945 0.3048)
			(end -0.67945 -0.305054)
			(stroke
				(width 0.1)
				(type default)
			)
			(layer "F.Fab")
		)
		(pad "1" smd circle
			(at -0.40005 0 90)
			(size 0 0)
			(layers "F.Cu" "F.Mask" "F.Paste")
			(net "P12V_AUX")
		)
		(pad "2" smd circle
			(at 0.40005 0 90)
			(size 0 0)
			(layers "F.Cu" "F.Mask" "F.Paste")
			(net "P12V_OCP_OV_FB_1")
		)
	)
	(footprint ""
		(layer "F.Cu")
		(at 89.131902 -373.03583 -90)
		(property "Reference" "C725"
			(at 0 0 270)
			(layer "F.SilkS")
			(hide yes)
			(effects
				(font
					(size 1.27 1.27)
				)
			)
		)
		(property "Value" ""
			(at 0 0 270)
			(layer "F.Fab")
			(effects
				(font
					(size 1.27 1.27)
				)
			)
		)
		(duplicate_pad_numbers_are_jumpers no)
		(fp_line
			(start -0.299974 0.150114)
			(end -0.299974 -0.150114)
			(stroke
				(width 0.1)
				(type default)
			)
			(layer "F.Fab")
		)
		(fp_line
			(start 0.299974 0.150114)
			(end -0.299974 0.150114)
			(stroke
				(width 0.1)
				(type default)
			)
			(layer "F.Fab")
		)
		(fp_line
			(start -0.299974 -0.150114)
			(end 0.299974 -0.150114)
			(stroke
				(width 0.1)
				(type default)
			)
			(layer "F.Fab")
		)
		(fp_line
			(start 0.299974 -0.150114)
			(end 0.299974 0.150114)
			(stroke
				(width 0.1)
				(type default)
			)
			(layer "F.Fab")
		)
		(pad "1" smd rect
			(at -0.2667 0 270)
			(size 0.3048 0.381)
			(layers "F.Cu" "F.Mask" "F.Paste")
			(net "P5E_CPU1_P1_TX_C_DP<8>")
		)
		(pad "2" smd rect
			(at 0.2667 0 270)
			(size 0.3048 0.381)
			(layers "F.Cu" "F.Mask" "F.Paste")
			(net "P5E_CPU1_P1_TX_DP<8>")
		)
	)
	(footprint ""
		(layer "F.Cu")
		(at 184.079642 -413.64408 -90)
		(property "Reference" "R2848"
			(at 0 0 270)
			(layer "F.SilkS")
			(hide yes)
			(effects
				(font
					(size 1.27 1.27)
				)
			)
		)
		(property "Value" ""
			(at 0 0 270)
			(layer "F.Fab")
			(effects
				(font
					(size 1.27 1.27)
				)
			)
		)
		(duplicate_pad_numbers_are_jumpers no)
		(fp_line
			(start -0.7874 0.4064)
			(end -0.7874 -0.4064)
			(stroke
				(width 0.1524)
				(type default)
			)
			(layer "F.SilkS")
		)
		(fp_line
			(start 0.7874 0.4064)
			(end -0.7874 0.4064)
			(stroke
				(width 0.1524)
				(type default)
			)
			(layer "F.SilkS")
		)
		(fp_line
			(start -0.7874 -0.4064)
			(end 0.7874 -0.4064)
			(stroke
				(width 0.1524)
				(type default)
			)
			(layer "F.SilkS")
		)
		(fp_line
			(start 0.7874 -0.4064)
			(end 0.7874 0.4064)
			(stroke
				(width 0.1524)
				(type default)
			)
			(layer "F.SilkS")
		)
		(fp_line
			(start -0.67945 0.3048)
			(end -0.67945 -0.305054)
			(stroke
				(width 0.1)
				(type default)
			)
			(layer "F.Fab")
		)
		(fp_line
			(start -0.12065 0.3048)
			(end -0.67945 0.3048)
			(stroke
				(width 0.1)
				(type default)
			)
			(layer "F.Fab")
		)
		(fp_line
			(start 0.120396 0.3048)
			(end 0.120396 0.2794)
			(stroke
				(width 0.1)
				(type default)
			)
			(layer "F.Fab")
		)
		(fp_line
			(start 0.67945 0.3048)
			(end 0.120396 0.3048)
			(stroke
				(width 0.1)
				(type default)
			)
			(layer "F.Fab")
		)
		(fp_line
			(start -0.12065 0.2794)
			(end -0.12065 0.3048)
			(stroke
				(width 0.1)
				(type default)
			)
			(layer "F.Fab")
		)
		(fp_line
			(start 0.120396 0.2794)
			(end -0.12065 0.2794)
			(stroke
				(width 0.1)
				(type default)
			)
			(layer "F.Fab")
		)
		(fp_line
			(start -0.12065 -0.2794)
			(end 0.12065 -0.2794)
			(stroke
				(width 0.1)
				(type default)
			)
			(layer "F.Fab")
		)
		(fp_line
			(start 0.12065 -0.2794)
			(end 0.12065 -0.3048)
			(stroke
				(width 0.1)
				(type default)
			)
			(layer "F.Fab")
		)
		(fp_line
			(start 0.12065 -0.3048)
			(end 0.67945 -0.3048)
			(stroke
				(width 0.1)
				(type default)
			)
			(layer "F.Fab")
		)
		(fp_line
			(start 0.67945 -0.3048)
			(end 0.67945 0.3048)
			(stroke
				(width 0.1)
				(type default)
			)
			(layer "F.Fab")
		)
		(fp_line
			(start -0.67945 -0.305054)
			(end -0.12065 -0.305054)
			(stroke
				(width 0.1)
				(type default)
			)
			(layer "F.Fab")
		)
		(fp_line
			(start -0.12065 -0.305054)
			(end -0.12065 -0.2794)
			(stroke
				(width 0.1)
				(type default)
			)
			(layer "F.Fab")
		)
		(pad "1" smd circle
			(at -0.40005 0 270)
			(size 0 0)
			(layers "F.Cu" "F.Mask" "F.Paste")
			(net "RST_SWB_BIC_N")
		)
		(pad "2" smd circle
			(at 0.40005 0 270)
			(size 0 0)
			(layers "F.Cu" "F.Mask" "F.Paste")
			(net "RST_SWB_BIC_R_N")
		)
	)
)
